(kicad_pcb
	(version 20241229)
	(generator "pcbnew")
	(generator_version "9.0")
	(general
		(thickness 1.552)
		(legacy_teardrops no)
	)
	(paper "A4")
	(title_block
		(date "2023-07-25")
		(rev "1.1.4")
		(comment 9 "footprints 345-349 of 379")
	)
	(layers
		(0 "F.Cu" signal)
		(4 "In1.Cu" signal)
		(6 "In2.Cu" signal)
		(8 "In3.Cu" signal)
		(10 "In4.Cu" signal)
		(12 "In5.Cu" signal)
		(14 "In6.Cu" signal)
		(2 "B.Cu" signal)
		(9 "F.Adhes" user "F.Adhesive")
		(11 "B.Adhes" user "B.Adhesive")
		(13 "F.Paste" user)
		(15 "B.Paste" user)
		(5 "F.SilkS" user "F.Silkscreen")
		(7 "B.SilkS" user "B.Silkscreen")
		(1 "F.Mask" user)
		(3 "B.Mask" user)
		(17 "Dwgs.User" user "User.Drawings")
		(19 "Cmts.User" user "User.Comments")
		(21 "Eco1.User" user "User.Eco1")
		(23 "Eco2.User" user "User.Eco2")
		(25 "Edge.Cuts" user)
		(27 "Margin" user)
		(31 "F.CrtYd" user "F.Courtyard")
		(29 "B.CrtYd" user "B.Courtyard")
		(35 "F.Fab" user)
		(33 "B.Fab" user)
	)
	(footprint "antmicro-footprints:C_0402_1005Metric"
		(layer "B.Cu")
		(at 119.02 62.41)
		(descr "Capacitor SMD 0402")
		(tags "capacitor SMD 0402")
		(property "Reference" "C44"
			(at -5.09 0.33 0)
			(layer "B.SilkS")
			(effects
				(font
					(size 0.65 0.65)
					(thickness 0.15)
				)
				(justify right bottom mirror)
			)
		)
		(property "Value" "C_100n_0402"
			(at 0 -1.4 0)
			(layer "B.Fab")
			(hide yes)
			(effects
				(font
					(size 0.7 0.7)
					(thickness 0.15)
				)
				(justify right bottom mirror)
			)
		)
		(property "Datasheet" "https://www.murata.com/products/productdetail?partno=GRM155R61H104KE14%23"
			(at 0 0 0)
			(layer "F.Fab")
			(hide yes)
			(effects
				(font
					(size 1.27 1.27)
					(thickness 0.15)
				)
			)
		)
		(property "Description" "SMD Multilayer Ceramic Capacitor, 0.1 µF, 50 V, 0402 [1005 Metric], ± 10%, X5R, GRM Series"
			(at 0 0 0)
			(layer "F.Fab")
			(hide yes)
			(effects
				(font
					(size 1.27 1.27)
					(thickness 0.15)
				)
			)
		)
		(property "Author" "Antmicro"
			(at 0 0 0)
			(layer "B.Fab")
			(hide yes)
			(effects
				(font
					(size 1 1)
					(thickness 0.15)
				)
				(justify mirror)
			)
		)
		(property "Dielectric" "X5R"
			(at 0 0 0)
			(layer "B.Fab")
			(hide yes)
			(effects
				(font
					(size 1 1)
					(thickness 0.15)
				)
				(justify mirror)
			)
		)
		(property "License" "Apache-2.0"
			(at 0 0 0)
			(layer "B.Fab")
			(hide yes)
			(effects
				(font
					(size 1 1)
					(thickness 0.15)
				)
				(justify mirror)
			)
		)
		(property "MPN" "GRM155R61H104KE14D"
			(at 0 0 0)
			(layer "B.Fab")
			(hide yes)
			(effects
				(font
					(size 1 1)
					(thickness 0.15)
				)
				(justify mirror)
			)
		)
		(property "Manufacturer" "Murata"
			(at 0 0 0)
			(layer "B.Fab")
			(hide yes)
			(effects
				(font
					(size 1 1)
					(thickness 0.15)
				)
				(justify mirror)
			)
		)
		(property "Val" "100n"
			(at 0 0 0)
			(layer "B.Fab")
			(hide yes)
			(effects
				(font
					(size 1 1)
					(thickness 0.15)
				)
				(justify mirror)
			)
		)
		(property "Voltage" "50V"
			(at 0 0 0)
			(layer "B.Fab")
			(hide yes)
			(effects
				(font
					(size 1 1)
					(thickness 0.15)
				)
				(justify mirror)
			)
		)
		(sheetname "/DDR3/")
		(sheetfile "ddr3.kicad_sch")
		(attr smd)
		(fp_rect
			(start -0.925 0.47)
			(end 0.925 -0.47)
			(stroke
				(width 0.05)
				(type default)
			)
			(fill no)
			(layer "B.CrtYd")
		)
		(fp_line
			(start -0.494 -0.248)
			(end -0.494 0.25)
			(stroke
				(width 0.15)
				(type solid)
			)
			(layer "B.Fab")
		)
		(fp_line
			(start -0.494 0.25)
			(end 0.504 0.25)
			(stroke
				(width 0.15)
				(type solid)
			)
			(layer "B.Fab")
		)
		(fp_line
			(start 0.504 -0.248)
			(end -0.494 -0.248)
			(stroke
				(width 0.15)
				(type solid)
			)
			(layer "B.Fab")
		)
		(fp_line
			(start 0.504 0.25)
			(end 0.504 -0.248)
			(stroke
				(width 0.15)
				(type solid)
			)
			(layer "B.Fab")
		)
		(fp_text user "${REFERENCE}"
			(at -0.939 -4.599 180)
			(layer "B.Fab")
			(effects
				(font
					(size 0.7 0.7)
					(thickness 0.15)
				)
				(justify left bottom mirror)
			)
		)
		(fp_text user "License: Apache-2.0"
			(at -0.939 -5.799 180)
			(layer "B.Fab")
			(effects
				(font
					(size 0.7 0.7)
					(thickness 0.15)
				)
				(justify left bottom mirror)
			)
		)
		(fp_text user "Author: Antmicro"
			(at -0.939 -3.399 180)
			(layer "B.Fab")
			(effects
				(font
					(size 0.7 0.7)
					(thickness 0.15)
				)
				(justify left bottom mirror)
			)
		)
		(pad "1" smd roundrect
			(at -0.48 0)
			(size 0.59 0.64)
			(layers "B.Cu" "B.Mask" "B.Paste")
			(roundrect_rratio 0.25)
			(net 1 "GND")
			(pintype "passive")
		)
		(pad "2" smd roundrect
			(at 0.48 0)
			(size 0.59 0.64)
			(layers "B.Cu" "B.Mask" "B.Paste")
			(roundrect_rratio 0.25)
			(net 248 "+1V5")
			(pintype "passive")
		)
	)
	(footprint "antmicro-footprints:C_0201"
		(layer "B.Cu")
		(at 134.63 92.2)
		(descr "Capacitor SMD 0201")
		(tags "capacitor SMD 0201")
		(property "Reference" "C94"
			(at -0.85 1.34 0)
			(layer "B.SilkS")
			(effects
				(font
					(size 0.65 0.65)
					(thickness 0.15)
				)
				(justify right bottom mirror)
			)
		)
		(property "Value" "C_100n_0201"
			(at 0 -1.4 0)
			(layer "B.Fab")
			(hide yes)
			(effects
				(font
					(size 0.7 0.7)
					(thickness 0.15)
				)
				(justify right bottom mirror)
			)
		)
		(property "Datasheet" "https://www.yageo.com/en/Chart/Download/pdf/CC0201KRX6S5BB104"
			(at 0 0 0)
			(layer "F.Fab")
			(hide yes)
			(effects
				(font
					(size 1.27 1.27)
					(thickness 0.15)
				)
			)
		)
		(property "Description" "SMD Multilayer Ceramic Capacitor, 0.1 µF, 6.3 V, 0201 [0603 Metric], ± 10%, X6S, CC Series"
			(at 0 0 0)
			(layer "F.Fab")
			(hide yes)
			(effects
				(font
					(size 1.27 1.27)
					(thickness 0.15)
				)
			)
		)
		(property "Author" "Antmicro"
			(at 0 0 0)
			(layer "B.Fab")
			(hide yes)
			(effects
				(font
					(size 1 1)
					(thickness 0.15)
				)
				(justify mirror)
			)
		)
		(property "Dielectric" ""
			(at 0 0 0)
			(layer "B.Fab")
			(hide yes)
			(effects
				(font
					(size 1 1)
					(thickness 0.15)
				)
				(justify mirror)
			)
		)
		(property "License" "Apache-2.0"
			(at 0 0 0)
			(layer "B.Fab")
			(hide yes)
			(effects
				(font
					(size 1 1)
					(thickness 0.15)
				)
				(justify mirror)
			)
		)
		(property "MPN" "CC0201KRX6S5BB104"
			(at 0 0 0)
			(layer "B.Fab")
			(hide yes)
			(effects
				(font
					(size 1 1)
					(thickness 0.15)
				)
				(justify mirror)
			)
		)
		(property "Manufacturer" "YAGEO"
			(at 0 0 0)
			(layer "B.Fab")
			(hide yes)
			(effects
				(font
					(size 1 1)
					(thickness 0.15)
				)
				(justify mirror)
			)
		)
		(property "Val" "100n"
			(at 0 0 0)
			(layer "B.Fab")
			(hide yes)
			(effects
				(font
					(size 1 1)
					(thickness 0.15)
				)
				(justify mirror)
			)
		)
		(property "Voltage" ""
			(at 0 0 0)
			(layer "B.Fab")
			(hide yes)
			(effects
				(font
					(size 1 1)
					(thickness 0.15)
				)
				(justify mirror)
			)
		)
		(property "Public" "False"
			(at 0 0 0)
			(unlocked yes)
			(layer "B.Fab")
			(hide yes)
			(effects
				(font
					(size 1 1)
					(thickness 0.15)
				)
				(justify mirror)
			)
		)
		(sheetname "/FPGA Power/")
		(sheetfile "FPGA_Power.kicad_sch")
		(attr smd)
		(fp_rect
			(start -0.7 0.35)
			(end 0.7 -0.35)
			(stroke
				(width 0.05)
				(type default)
			)
			(fill no)
			(layer "B.CrtYd")
		)
		(fp_rect
			(start 0.3 -0.15)
			(end -0.301 0.149)
			(stroke
				(width 0.15)
				(type solid)
			)
			(fill no)
			(layer "B.Fab")
		)
		(fp_text user "License: Apache-2.0"
			(at -0.72 -4.4 180)
			(layer "B.Fab")
			(effects
				(font
					(size 0.7 0.7)
					(thickness 0.15)
				)
				(justify left bottom mirror)
			)
		)
		(fp_text user "Author: Antmicro"
			(at -0.72 -5.4 180)
			(layer "B.Fab")
			(effects
				(font
					(size 0.7 0.7)
					(thickness 0.15)
				)
				(justify left bottom mirror)
			)
		)
		(fp_text user "${REFERENCE}"
			(at -0.72 -3.4 180)
			(layer "B.Fab")
			(effects
				(font
					(size 0.7 0.7)
					(thickness 0.15)
				)
				(justify left bottom mirror)
			)
		)
		(pad "" smd roundrect
			(at -0.349 0.002)
			(size 0.318 0.36)
			(layers "B.Paste")
			(roundrect_rratio 0.25)
		)
		(pad "" smd roundrect
			(at 0.341 0.002)
			(size 0.318 0.36)
			(layers "B.Paste")
			(roundrect_rratio 0.25)
		)
		(pad "1" smd roundrect
			(at -0.321 0.002)
			(size 0.46 0.4)
			(layers "B.Cu" "B.Mask")
			(roundrect_rratio 0.25)
			(net 1 "GND")
			(pintype "passive")
		)
		(pad "2" smd roundrect
			(at 0.32 0.002)
			(size 0.46 0.4)
			(layers "B.Cu" "B.Mask")
			(roundrect_rratio 0.25)
			(net 10 "/FPGA Power/VCC_AUXA")
			(pintype "passive")
		)
	)
	(footprint "antmicro-footprints:SOT-363"
		(layer "B.Cu")
		(at 154.23 65.75 -90)
		(property "Reference" "Q2"
			(at 2.19 -0.1 180)
			(layer "B.SilkS")
			(effects
				(font
					(size 0.65 0.65)
					(thickness 0.15)
				)
				(justify left bottom mirror)
			)
		)
		(property "Value" "BCM857BS-7-F"
			(at 0 -2.2 90)
			(layer "B.Fab")
			(hide yes)
			(effects
				(font
					(size 0.7 0.7)
					(thickness 0.15)
				)
				(justify left bottom mirror)
			)
		)
		(property "Datasheet" "https://www.diodes.com/assets/Datasheets/BCM857BS.pdf"
			(at 0 0 270)
			(layer "F.Fab")
			(hide yes)
			(effects
				(font
					(size 1.27 1.27)
					(thickness 0.15)
				)
			)
		)
		(property "Description" "Bipolar (BJT) Transistor Array, 2 Transistors, PNP, 45V, 100mA, SOT-363, Surface Mount"
			(at 0 0 270)
			(layer "F.Fab")
			(hide yes)
			(effects
				(font
					(size 1.27 1.27)
					(thickness 0.15)
				)
			)
		)
		(property "Author" "Antmicro"
			(at 88.48 219.98 0)
			(layer "B.Fab")
			(hide yes)
			(effects
				(font
					(size 1 1)
					(thickness 0.15)
				)
				(justify mirror)
			)
		)
		(property "License" "Apache-2.0"
			(at 88.48 219.98 0)
			(layer "B.Fab")
			(hide yes)
			(effects
				(font
					(size 1 1)
					(thickness 0.15)
				)
				(justify mirror)
			)
		)
		(property "MPN" "BCM857BS-7-F"
			(at 88.48 219.98 0)
			(layer "B.Fab")
			(hide yes)
			(effects
				(font
					(size 1 1)
					(thickness 0.15)
				)
				(justify mirror)
			)
		)
		(property "Manufacturer" "Diodes Incorporated"
			(at 88.48 219.98 0)
			(layer "B.Fab")
			(hide yes)
			(effects
				(font
					(size 1 1)
					(thickness 0.15)
				)
				(justify mirror)
			)
		)
		(sheetname "/Power Supply/")
		(sheetfile "supply.kicad_sch")
		(attr smd)
		(fp_line
			(start 0.803 1.228)
			(end -0.72 1.228)
			(stroke
				(width 0.15)
				(type solid)
			)
			(layer "B.SilkS")
		)
		(fp_line
			(start -0.72 1.153)
			(end -0.72 1.228)
			(stroke
				(width 0.15)
				(type solid)
			)
			(layer "B.SilkS")
		)
		(fp_line
			(start 0.803 1.153)
			(end 0.803 1.228)
			(stroke
				(width 0.15)
				(type solid)
			)
			(layer "B.SilkS")
		)
		(fp_line
			(start -0.8 -1.146)
			(end -0.8 -1.223)
			(stroke
				(width 0.15)
				(type solid)
			)
			(layer "B.SilkS")
		)
		(fp_line
			(start 0.803 -1.146)
			(end 0.803 -1.223)
			(stroke
				(width 0.15)
				(type solid)
			)
			(layer "B.SilkS")
		)
		(fp_line
			(start -0.8 -1.223)
			(end 0.803 -1.223)
			(stroke
				(width 0.15)
				(type solid)
			)
			(layer "B.SilkS")
		)
		(fp_circle
			(center -0.978102 1.2)
			(end -0.928102 1.2)
			(stroke
				(width 0.15)
				(type solid)
			)
			(fill yes)
			(layer "B.SilkS")
		)
		(fp_rect
			(start 1.3 1.3)
			(end -1.3 -1.3)
			(stroke
				(width 0.05)
				(type solid)
			)
			(fill no)
			(layer "B.CrtYd")
		)
		(fp_line
			(start -0.1 1.1)
			(end -0.68 0.52)
			(stroke
				(width 0.15)
				(type solid)
			)
			(layer "B.Fab")
		)
		(fp_rect
			(start 0.68 -1.1)
			(end -0.68 1.1)
			(stroke
				(width 0.15)
				(type solid)
			)
			(fill no)
			(layer "B.Fab")
		)
		(pad "1" smd custom
			(at -0.948 0.752)
			(size 0.6 0.6)
			(layers "B.Cu" "B.Mask" "B.Paste")
			(net 304 "/Power Supply/5V_I")
			(pintype "passive")
			(zone_connect 0)
			(options
				(clearance outline)
				(anchor rect)
			)
			(primitives)
		)
		(pad "2" smd rect
			(at -0.948 0.002)
			(size 0.4 0.6)
			(layers "B.Cu" "B.Mask" "B.Paste")
			(net 382 "Net-(Q2-Pad2)")
			(pintype "input")
		)
		(pad "3" smd custom
			(at -0.948 -0.745)
			(size 0.6 0.6)
			(layers "B.Cu" "B.Mask" "B.Paste")
			(net 382 "Net-(Q2-Pad2)")
			(pintype "passive")
			(zone_connect 0)
			(options
				(clearance outline)
				(anchor rect)
			)
			(primitives)
		)
		(pad "4" smd custom
			(at 0.951 -0.745)
			(size 0.6 0.6)
			(layers "B.Cu" "B.Mask" "B.Paste")
			(net 325 "USB_POWER_IN")
			(pintype "passive")
			(zone_connect 0)
			(options
				(clearance outline)
				(anchor rect)
			)
			(primitives)
		)
		(pad "5" smd rect
			(at 0.951 0.002)
			(size 0.4 0.6)
			(layers "B.Cu" "B.Mask" "B.Paste")
			(net 382 "Net-(Q2-Pad2)")
			(pintype "input")
		)
		(pad "6" smd custom
			(at 0.951 0.752)
			(size 0.6 0.6)
			(layers "B.Cu" "B.Mask" "B.Paste")
			(net 260 "Net-(Q3-G)")
			(pintype "passive")
			(zone_connect 0)
			(options
				(clearance outline)
				(anchor rect)
			)
			(primitives)
		)
	)
	(footprint "antmicro-footprints:TP_SMD_0.75mm"
		(layer "B.Cu")
		(at 93.94 88.2 90)
		(property "Reference" "TP42"
			(at 0.76 0.39 90)
			(layer "B.SilkS")
			(effects
				(font
					(size 0.65 0.65)
					(thickness 0.15)
				)
				(justify right bottom mirror)
			)
		)
		(property "Value" "TP_0.75mm_SMD"
			(at 0 -1.2 90)
			(layer "B.Fab")
			(hide yes)
			(effects
				(font
					(size 0.7 0.7)
					(thickness 0.15)
				)
				(justify right bottom mirror)
			)
		)
		(property "Description" "SMT test point"
			(at 0 0 90)
			(layer "F.Fab")
			(hide yes)
			(effects
				(font
					(size 1.27 1.27)
					(thickness 0.15)
				)
			)
		)
		(property "Author" "Antmicro"
			(at 182.14 -5.74 0)
			(layer "B.Fab")
			(hide yes)
			(effects
				(font
					(size 1 1)
					(thickness 0.15)
				)
				(justify mirror)
			)
		)
		(property "License" "Apache-2.0"
			(at 182.14 -5.74 0)
			(layer "B.Fab")
			(hide yes)
			(effects
				(font
					(size 1 1)
					(thickness 0.15)
				)
				(justify mirror)
			)
		)
		(property "MPN" ""
			(at 182.14 -5.74 0)
			(layer "B.Fab")
			(hide yes)
			(effects
				(font
					(size 1 1)
					(thickness 0.15)
				)
				(justify mirror)
			)
		)
		(property "Manufacturer" ""
			(at 182.14 -5.74 0)
			(layer "B.Fab")
			(hide yes)
			(effects
				(font
					(size 1 1)
					(thickness 0.15)
				)
				(justify mirror)
			)
		)
		(sheetname "/SDI/")
		(sheetfile "sdi.kicad_sch")
		(attr exclude_from_pos_files)
		(fp_circle
			(center 0 0)
			(end 0.475 0)
			(stroke
				(width 0.05)
				(type default)
			)
			(fill no)
			(layer "B.CrtYd")
		)
		(fp_text user "Author: Antmicro"
			(at -0.4 -3.901 270)
			(layer "B.Fab")
			(effects
				(font
					(size 0.7 0.7)
					(thickness 0.15)
				)
				(justify left bottom mirror)
			)
		)
		(fp_text user "${REFERENCE}"
			(at -0.4 -2.7 270)
			(layer "B.Fab")
			(effects
				(font
					(size 0.7 0.7)
					(thickness 0.15)
				)
				(justify left bottom mirror)
			)
		)
		(fp_text user "License: Apache-2.0"
			(at -0.4 -5.101 270)
			(layer "B.Fab")
			(effects
				(font
					(size 0.7 0.7)
					(thickness 0.15)
				)
				(justify left bottom mirror)
			)
		)
		(pad "1" smd circle
			(at 0 0 90)
			(size 0.75 0.75)
			(layers "B.Cu" "B.Mask")
			(net 180 "/SDI/TIM_861")
			(pinfunction "1")
			(pintype "passive")
		)
	)
	(footprint "antmicro-footprints:C_0201"
		(layer "B.Cu")
		(at 132.3 84.3 -135)
		(descr "Capacitor SMD 0201")
		(tags "capacitor SMD 0201")
		(property "Reference" "C16"
			(at -0.982878 0.657609 45)
			(layer "B.SilkS")
			(effects
				(font
					(size 0.65 0.65)
					(thickness 0.15)
				)
				(justify left bottom mirror)
			)
		)
		(property "Value" "C_100n_0201"
			(at 0 -1.399999 45)
			(layer "B.Fab")
			(hide yes)
			(effects
				(font
					(size 0.7 0.7)
					(thickness 0.15)
				)
				(justify left bottom mirror)
			)
		)
		(property "Datasheet" "https://www.yageo.com/en/Chart/Download/pdf/CC0201KRX6S5BB104"
			(at 0 0 225)
			(layer "F.Fab")
			(hide yes)
			(effects
				(font
					(size 1.27 1.27)
					(thickness 0.15)
				)
			)
		)
		(property "Description" "SMD Multilayer Ceramic Capacitor, 0.1 µF, 6.3 V, 0201 [0603 Metric], ± 10%, X6S, CC Series"
			(at 0 0 225)
			(layer "F.Fab")
			(hide yes)
			(effects
				(font
					(size 1.27 1.27)
					(thickness 0.15)
				)
			)
		)
		(property "Author" "Antmicro"
			(at 166.241125 237.459329 0)
			(layer "B.Fab")
			(hide yes)
			(effects
				(font
					(size 1 1)
					(thickness 0.15)
				)
				(justify mirror)
			)
		)
		(property "Dielectric" ""
			(at 166.241125 237.459329 0)
			(layer "B.Fab")
			(hide yes)
			(effects
				(font
					(size 1 1)
					(thickness 0.15)
				)
				(justify mirror)
			)
		)
		(property "License" "Apache-2.0"
			(at 166.241125 237.459329 0)
			(layer "B.Fab")
			(hide yes)
			(effects
				(font
					(size 1 1)
					(thickness 0.15)
				)
				(justify mirror)
			)
		)
		(property "MPN" "CC0201KRX6S5BB104"
			(at 166.241125 237.459329 0)
			(layer "B.Fab")
			(hide yes)
			(effects
				(font
					(size 1 1)
					(thickness 0.15)
				)
				(justify mirror)
			)
		)
		(property "Manufacturer" "YAGEO"
			(at 166.241125 237.459329 0)
			(layer "B.Fab")
			(hide yes)
			(effects
				(font
					(size 1 1)
					(thickness 0.15)
				)
				(justify mirror)
			)
		)
		(property "Val" "100n"
			(at 166.241125 237.459329 0)
			(layer "B.Fab")
			(hide yes)
			(effects
				(font
					(size 1 1)
					(thickness 0.15)
				)
				(justify mirror)
			)
		)
		(property "Voltage" ""
			(at 166.241125 237.459329 0)
			(layer "B.Fab")
			(hide yes)
			(effects
				(font
					(size 1 1)
					(thickness 0.15)
				)
				(justify mirror)
			)
		)
		(property "Public" "False"
			(at 0 0 225)
			(unlocked yes)
			(layer "B.Fab")
			(hide yes)
			(effects
				(font
					(size 1 1)
					(thickness 0.15)
				)
				(justify mirror)
			)
		)
		(sheetname "/DDR3/")
		(sheetfile "ddr3.kicad_sch")
		(attr smd)
		(fp_poly
			(pts
				(xy -0.7 0.35) (xy 0.7 0.35) (xy 0.7 -0.35) (xy -0.7 -0.35)
			)
			(stroke
				(width 0.05)
				(type default)
			)
			(fill no)
			(layer "B.CrtYd")
		)
		(fp_poly
			(pts
				(xy 0.3 -0.15) (xy -0.301 -0.15) (xy -0.301 0.149) (xy 0.3 0.149)
			)
			(stroke
				(width 0.15)
				(type solid)
			)
			(fill no)
			(layer "B.Fab")
		)
		(fp_text user "Author: Antmicro"
			(at -0.72 -5.400001 45)
			(layer "B.Fab")
			(effects
				(font
					(size 0.7 0.7)
					(thickness 0.15)
				)
				(justify left bottom mirror)
			)
		)
		(fp_text user "License: Apache-2.0"
			(at -0.72 -4.4 45)
			(layer "B.Fab")
			(effects
				(font
					(size 0.7 0.7)
					(thickness 0.15)
				)
				(justify left bottom mirror)
			)
		)
		(fp_text user "${REFERENCE}"
			(at -0.72 -3.4 45)
			(layer "B.Fab")
			(effects
				(font
					(size 0.7 0.7)
					(thickness 0.15)
				)
				(justify left bottom mirror)
			)
		)
		(pad "" smd roundrect
			(at -0.349 0.002 225)
			(size 0.318 0.36)
			(layers "B.Paste")
			(roundrect_rratio 0.25)
		)
		(pad "" smd roundrect
			(at 0.341 0.002 225)
			(size 0.318 0.36)
			(layers "B.Paste")
			(roundrect_rratio 0.25)
		)
		(pad "1" smd roundrect
			(at -0.321 0.002 225)
			(size 0.46 0.4)
			(layers "B.Cu" "B.Mask")
			(roundrect_rratio 0.25)
			(net 1 "GND")
			(pintype "passive")
		)
		(pad "2" smd roundrect
			(at 0.32 0.002 225)
			(size 0.46 0.4)
			(layers "B.Cu" "B.Mask")
			(roundrect_rratio 0.25)
			(net 248 "+1V5")
			(pintype "passive")
		)
	)
)
